(kicad_sch (version 20230121) (generator eeschema)

  (paper "A3")

  (title_block
    (title "Scalenode CM4 Baseboard")
    (date "2024-03-26")
    (rev "1.1.3")
    (company "Antmicro")
    (comment 1 "www.antmicro.com")
  )

  (junction (at 198.12 97.79) (diameter 0) (color 0 0 0 0)
  )
  (junction (at 170.18 95.25) (diameter 0) (color 0 0 0 0)
  )
  (junction (at 198.12 118.11) (diameter 0) (color 0 0 0 0)
  )
  (junction (at 170.18 97.79) (diameter 0) (color 0 0 0 0)
  )
  (junction (at 198.12 113.03) (diameter 0) (color 0 0 0 0)
  )
  (junction (at 198.12 115.57) (diameter 0) (color 0 0 0 0)
  )
  (junction (at 198.12 92.71) (diameter 0) (color 0 0 0 0)
  )
  (junction (at 170.18 118.11) (diameter 0) (color 0 0 0 0)
  )
  (junction (at 198.12 135.89) (diameter 0) (color 0 0 0 0)
  )
  (junction (at 170.18 113.03) (diameter 0) (color 0 0 0 0)
  )
  (junction (at 170.18 156.21) (diameter 0) (color 0 0 0 0)
  )
  (junction (at 170.18 100.33) (diameter 0) (color 0 0 0 0)
  )
  (junction (at 198.12 128.27) (diameter 0) (color 0 0 0 0)
  )
  (junction (at 198.12 90.17) (diameter 0) (color 0 0 0 0)
  )
  (junction (at 198.12 168.91) (diameter 0) (color 0 0 0 0)
  )
  (junction (at 170.18 163.83) (diameter 0) (color 0 0 0 0)
  )
  (junction (at 170.18 133.35) (diameter 0) (color 0 0 0 0)
  )
  (junction (at 198.12 120.65) (diameter 0) (color 0 0 0 0)
  )
  (junction (at 198.12 143.51) (diameter 0) (color 0 0 0 0)
  )
  (junction (at 170.18 92.71) (diameter 0) (color 0 0 0 0)
  )
  (junction (at 198.12 95.25) (diameter 0) (color 0 0 0 0)
  )
  (junction (at 198.12 158.75) (diameter 0) (color 0 0 0 0)
  )
  (junction (at 170.18 120.65) (diameter 0) (color 0 0 0 0)
  )
  (junction (at 170.18 148.59) (diameter 0) (color 0 0 0 0)
  )
  (junction (at 198.12 100.33) (diameter 0) (color 0 0 0 0)
  )
  (junction (at 198.12 151.13) (diameter 0) (color 0 0 0 0)
  )
  (junction (at 170.18 90.17) (diameter 0) (color 0 0 0 0)
  )
  (junction (at 170.18 140.97) (diameter 0) (color 0 0 0 0)
  )
  (junction (at 170.18 115.57) (diameter 0) (color 0 0 0 0)
  )

  (no_connect (at 175.26 196.85))
  (no_connect (at 135.255 196.215))
  (no_connect (at 213.36 196.85))
  (no_connect (at 193.04 105.41))
  (no_connect (at 172.72 105.41))
  (no_connect (at 172.72 107.95))
  (no_connect (at 193.04 107.95))

  (wire (pts (xy 257.81 99.06) (xy 264.16 99.06))
    (stroke (width 0) (type default))
  )
  (wire (pts (xy 269.24 104.14) (xy 274.32 104.14))
    (stroke (width 0) (type default))
  )
  (wire (pts (xy 198.12 95.25) (xy 198.12 92.71))
    (stroke (width 0) (type default))
  )
  (wire (pts (xy 172.72 97.79) (xy 170.18 97.79))
    (stroke (width 0) (type default))
  )
  (wire (pts (xy 198.12 158.75) (xy 198.12 168.91))
    (stroke (width 0) (type default))
  )
  (wire (pts (xy 198.12 168.91) (xy 193.04 168.91))
    (stroke (width 0) (type default))
  )
  (wire (pts (xy 172.72 123.19) (xy 167.64 123.19))
    (stroke (width 0) (type default))
  )
  (wire (pts (xy 170.18 92.71) (xy 170.18 95.25))
    (stroke (width 0) (type default))
  )
  (wire (pts (xy 193.04 115.57) (xy 198.12 115.57))
    (stroke (width 0) (type default))
  )
  (wire (pts (xy 170.18 115.57) (xy 170.18 113.03))
    (stroke (width 0) (type default))
  )
  (wire (pts (xy 172.72 151.13) (xy 167.64 151.13))
    (stroke (width 0) (type default))
  )
  (wire (pts (xy 170.18 140.97) (xy 170.18 148.59))
    (stroke (width 0) (type default))
  )
  (wire (pts (xy 198.12 128.27) (xy 193.04 128.27))
    (stroke (width 0) (type default))
  )
  (wire (pts (xy 172.72 95.25) (xy 170.18 95.25))
    (stroke (width 0) (type default))
  )
  (wire (pts (xy 167.64 90.17) (xy 170.18 90.17))
    (stroke (width 0) (type default))
  )
  (wire (pts (xy 170.18 118.11) (xy 170.18 115.57))
    (stroke (width 0) (type default))
  )
  (wire (pts (xy 198.12 110.49) (xy 198.12 113.03))
    (stroke (width 0) (type default))
  )
  (wire (pts (xy 193.04 90.17) (xy 198.12 90.17))
    (stroke (width 0) (type default))
  )
  (wire (pts (xy 193.04 130.81) (xy 200.66 130.81))
    (stroke (width 0) (type default))
  )
  (wire (pts (xy 170.18 97.79) (xy 170.18 100.33))
    (stroke (width 0) (type default))
  )
  (wire (pts (xy 193.04 140.97) (xy 200.66 140.97))
    (stroke (width 0) (type default))
  )
  (wire (pts (xy 198.12 151.13) (xy 198.12 143.51))
    (stroke (width 0) (type default))
  )
  (wire (pts (xy 200.66 148.59) (xy 193.04 148.59))
    (stroke (width 0) (type default))
  )
  (wire (pts (xy 198.12 118.11) (xy 198.12 115.57))
    (stroke (width 0) (type default))
  )
  (wire (pts (xy 170.18 92.71) (xy 170.18 90.17))
    (stroke (width 0) (type default))
  )
  (wire (pts (xy 172.72 125.73) (xy 167.64 125.73))
    (stroke (width 0) (type default))
  )
  (wire (pts (xy 198.12 120.65) (xy 198.12 118.11))
    (stroke (width 0) (type default))
  )
  (wire (pts (xy 193.04 113.03) (xy 198.12 113.03))
    (stroke (width 0) (type default))
  )
  (wire (pts (xy 172.72 138.43) (xy 167.64 138.43))
    (stroke (width 0) (type default))
  )
  (wire (pts (xy 193.04 146.05) (xy 200.66 146.05))
    (stroke (width 0) (type default))
  )
  (wire (pts (xy 193.04 100.33) (xy 198.12 100.33))
    (stroke (width 0) (type default))
  )
  (wire (pts (xy 198.12 135.89) (xy 198.12 128.27))
    (stroke (width 0) (type default))
  )
  (wire (pts (xy 193.04 97.79) (xy 198.12 97.79))
    (stroke (width 0) (type default))
  )
  (wire (pts (xy 198.12 168.91) (xy 198.12 173.99))
    (stroke (width 0) (type default))
  )
  (wire (pts (xy 172.72 148.59) (xy 170.18 148.59))
    (stroke (width 0) (type default))
  )
  (wire (pts (xy 198.12 143.51) (xy 198.12 135.89))
    (stroke (width 0) (type default))
  )
  (wire (pts (xy 172.72 153.67) (xy 167.64 153.67))
    (stroke (width 0) (type default))
  )
  (wire (pts (xy 172.72 118.11) (xy 170.18 118.11))
    (stroke (width 0) (type default))
  )
  (wire (pts (xy 193.04 120.65) (xy 198.12 120.65))
    (stroke (width 0) (type default))
  )
  (wire (pts (xy 170.18 113.03) (xy 170.18 110.49))
    (stroke (width 0) (type default))
  )
  (wire (pts (xy 193.04 102.87) (xy 198.12 102.87))
    (stroke (width 0) (type default))
  )
  (wire (pts (xy 172.72 135.89) (xy 167.64 135.89))
    (stroke (width 0) (type default))
  )
  (wire (pts (xy 172.72 133.35) (xy 170.18 133.35))
    (stroke (width 0) (type default))
  )
  (wire (pts (xy 200.66 125.73) (xy 193.04 125.73))
    (stroke (width 0) (type default))
  )
  (wire (pts (xy 257.81 104.14) (xy 264.16 104.14))
    (stroke (width 0) (type default))
  )
  (wire (pts (xy 170.18 163.83) (xy 170.18 173.99))
    (stroke (width 0) (type default))
  )
  (wire (pts (xy 170.18 120.65) (xy 172.72 120.65))
    (stroke (width 0) (type default))
  )
  (wire (pts (xy 198.12 128.27) (xy 198.12 120.65))
    (stroke (width 0) (type default))
  )
  (wire (pts (xy 193.04 161.29) (xy 200.66 161.29))
    (stroke (width 0) (type default))
  )
  (wire (pts (xy 198.12 113.03) (xy 198.12 115.57))
    (stroke (width 0) (type default))
  )
  (wire (pts (xy 198.12 90.17) (xy 198.12 92.71))
    (stroke (width 0) (type default))
  )
  (wire (pts (xy 198.12 90.17) (xy 200.66 90.17))
    (stroke (width 0) (type default))
  )
  (wire (pts (xy 172.72 156.21) (xy 170.18 156.21))
    (stroke (width 0) (type default))
  )
  (wire (pts (xy 198.12 102.87) (xy 198.12 100.33))
    (stroke (width 0) (type default))
  )
  (wire (pts (xy 170.18 102.87) (xy 170.18 100.33))
    (stroke (width 0) (type default))
  )
  (wire (pts (xy 172.72 102.87) (xy 170.18 102.87))
    (stroke (width 0) (type default))
  )
  (wire (pts (xy 172.72 143.51) (xy 167.64 143.51))
    (stroke (width 0) (type default))
  )
  (wire (pts (xy 172.72 92.71) (xy 170.18 92.71))
    (stroke (width 0) (type default))
  )
  (wire (pts (xy 269.24 99.06) (xy 274.32 99.06))
    (stroke (width 0) (type default))
  )
  (wire (pts (xy 172.72 163.83) (xy 170.18 163.83))
    (stroke (width 0) (type default))
  )
  (wire (pts (xy 172.72 130.81) (xy 167.64 130.81))
    (stroke (width 0) (type default))
  )
  (wire (pts (xy 170.18 156.21) (xy 170.18 163.83))
    (stroke (width 0) (type default))
  )
  (wire (pts (xy 172.72 113.03) (xy 170.18 113.03))
    (stroke (width 0) (type default))
  )
  (wire (pts (xy 198.12 151.13) (xy 198.12 158.75))
    (stroke (width 0) (type default))
  )
  (wire (pts (xy 170.18 120.65) (xy 170.18 133.35))
    (stroke (width 0) (type default))
  )
  (wire (pts (xy 193.04 138.43) (xy 200.66 138.43))
    (stroke (width 0) (type default))
  )
  (wire (pts (xy 193.04 143.51) (xy 198.12 143.51))
    (stroke (width 0) (type default))
  )
  (wire (pts (xy 172.72 158.75) (xy 167.64 158.75))
    (stroke (width 0) (type default))
  )
  (wire (pts (xy 172.72 161.29) (xy 167.64 161.29))
    (stroke (width 0) (type default))
  )
  (wire (pts (xy 198.12 158.75) (xy 193.04 158.75))
    (stroke (width 0) (type default))
  )
  (wire (pts (xy 172.72 90.17) (xy 170.18 90.17))
    (stroke (width 0) (type default))
  )
  (wire (pts (xy 200.66 123.19) (xy 193.04 123.19))
    (stroke (width 0) (type default))
  )
  (wire (pts (xy 170.18 115.57) (xy 172.72 115.57))
    (stroke (width 0) (type default))
  )
  (wire (pts (xy 198.12 97.79) (xy 198.12 95.25))
    (stroke (width 0) (type default))
  )
  (wire (pts (xy 193.04 118.11) (xy 198.12 118.11))
    (stroke (width 0) (type default))
  )
  (wire (pts (xy 170.18 100.33) (xy 172.72 100.33))
    (stroke (width 0) (type default))
  )
  (wire (pts (xy 193.04 135.89) (xy 198.12 135.89))
    (stroke (width 0) (type default))
  )
  (wire (pts (xy 170.18 133.35) (xy 170.18 140.97))
    (stroke (width 0) (type default))
  )
  (wire (pts (xy 193.04 156.21) (xy 200.66 156.21))
    (stroke (width 0) (type default))
  )
  (wire (pts (xy 193.04 153.67) (xy 200.66 153.67))
    (stroke (width 0) (type default))
  )
  (wire (pts (xy 170.18 97.79) (xy 170.18 95.25))
    (stroke (width 0) (type default))
  )
  (wire (pts (xy 198.12 92.71) (xy 193.04 92.71))
    (stroke (width 0) (type default))
  )
  (wire (pts (xy 170.18 148.59) (xy 170.18 156.21))
    (stroke (width 0) (type default))
  )
  (wire (pts (xy 193.04 95.25) (xy 198.12 95.25))
    (stroke (width 0) (type default))
  )
  (wire (pts (xy 193.04 163.83) (xy 200.66 163.83))
    (stroke (width 0) (type default))
  )
  (wire (pts (xy 170.18 110.49) (xy 172.72 110.49))
    (stroke (width 0) (type default))
  )
  (wire (pts (xy 172.72 140.97) (xy 170.18 140.97))
    (stroke (width 0) (type default))
  )
  (wire (pts (xy 170.18 120.65) (xy 170.18 118.11))
    (stroke (width 0) (type default))
  )
  (wire (pts (xy 172.72 128.27) (xy 167.64 128.27))
    (stroke (width 0) (type default))
  )
  (wire (pts (xy 193.04 110.49) (xy 198.12 110.49))
    (stroke (width 0) (type default))
  )
  (wire (pts (xy 172.72 146.05) (xy 167.64 146.05))
    (stroke (width 0) (type default))
  )
  (wire (pts (xy 193.04 133.35) (xy 200.66 133.35))
    (stroke (width 0) (type default))
  )
  (wire (pts (xy 193.04 151.13) (xy 198.12 151.13))
    (stroke (width 0) (type default))
  )
  (wire (pts (xy 198.12 97.79) (xy 198.12 100.33))
    (stroke (width 0) (type default))
  )

  (text "LSHM connector current rating:\n2A per pin (2 pins powered)"
    (at 245.11 82.55 0)
    (effects (font (size 1.27 1.27)) (justify right bottom))
  )
  (text "3V3 source select" (at 276.225 92.71 0)
    (effects (font (size 1.27 1.27)) (justify right bottom))
  )
  (text "Communication adapter connector" (at 148.59 66.04 0)
    (effects (font (size 2.9972 2.9972) (thickness 0.5994) bold) (justify left bottom))
  )

  (global_label "SCL0" (shape input) (at 200.66 138.43 0) (fields_autoplaced)
    (effects (font (size 1.27 1.27)) (justify left))
    (property "Intersheetrefs" "${INTERSHEET_REFS}" (at -8.255 3.175 0)
      (effects (font (size 1.27 1.27)) hide)
    )
  )
  (global_label "HDMI0_CK_N" (shape input) (at 167.64 161.29 180) (fields_autoplaced)
    (effects (font (size 1.27 1.27)) (justify right))
    (property "Intersheetrefs" "${INTERSHEET_REFS}" (at 0.635 3.175 0)
      (effects (font (size 1.27 1.27)) hide)
    )
  )
  (global_label "3V3_RPi" (shape input) (at 274.32 104.14 0) (fields_autoplaced)
    (effects (font (size 1.27 1.27)) (justify left))
    (property "Intersheetrefs" "${INTERSHEET_REFS}" (at -3.175 1.27 0)
      (effects (font (size 1.27 1.27)) hide)
    )
  )
  (global_label "HDMI0_CK_P" (shape input) (at 167.64 158.75 180) (fields_autoplaced)
    (effects (font (size 1.27 1.27)) (justify right))
    (property "Intersheetrefs" "${INTERSHEET_REFS}" (at 0.635 3.175 0)
      (effects (font (size 1.27 1.27)) hide)
    )
  )
  (global_label "3V3_OUT" (shape input) (at 257.81 104.14 180) (fields_autoplaced)
    (effects (font (size 1.27 1.27)) (justify right))
    (property "Intersheetrefs" "${INTERSHEET_REFS}" (at -0.635 1.27 0)
      (effects (font (size 1.27 1.27)) hide)
    )
  )
  (global_label "HDMI0_SDA" (shape input) (at 167.64 125.73 180) (fields_autoplaced)
    (effects (font (size 1.27 1.27)) (justify right))
    (property "Intersheetrefs" "${INTERSHEET_REFS}" (at 0.635 3.175 0)
      (effects (font (size 1.27 1.27)) hide)
    )
  )
  (global_label "GPIO26" (shape input) (at 200.66 146.05 0) (fields_autoplaced)
    (effects (font (size 1.27 1.27)) (justify left))
    (property "Intersheetrefs" "${INTERSHEET_REFS}" (at -8.255 3.175 0)
      (effects (font (size 1.27 1.27)) hide)
    )
  )
  (global_label "Adapter_RXD" (shape input) (at 200.66 123.19 0) (fields_autoplaced)
    (effects (font (size 1.27 1.27)) (justify left))
    (property "Intersheetrefs" "${INTERSHEET_REFS}" (at -7.62 3.175 0)
      (effects (font (size 1.27 1.27)) hide)
    )
  )
  (global_label "GPIO7" (shape input) (at 200.66 153.67 0) (fields_autoplaced)
    (effects (font (size 1.27 1.27)) (justify left))
    (property "Intersheetrefs" "${INTERSHEET_REFS}" (at -8.255 3.175 0)
      (effects (font (size 1.27 1.27)) hide)
    )
  )
  (global_label "GPIO18" (shape input) (at 200.66 148.59 0) (fields_autoplaced)
    (effects (font (size 1.27 1.27)) (justify left))
    (property "Intersheetrefs" "${INTERSHEET_REFS}" (at -8.255 3.175 0)
      (effects (font (size 1.27 1.27)) hide)
    )
  )
  (global_label "HDMI0_D2_P" (shape input) (at 167.64 135.89 180) (fields_autoplaced)
    (effects (font (size 1.27 1.27)) (justify right))
    (property "Intersheetrefs" "${INTERSHEET_REFS}" (at 0.635 3.175 0)
      (effects (font (size 1.27 1.27)) hide)
    )
  )
  (global_label "HDMI0_D2_N" (shape input) (at 167.64 138.43 180) (fields_autoplaced)
    (effects (font (size 1.27 1.27)) (justify right))
    (property "Intersheetrefs" "${INTERSHEET_REFS}" (at 0.635 3.175 0)
      (effects (font (size 1.27 1.27)) hide)
    )
  )
  (global_label "3V3_OUT" (shape input) (at 257.81 99.06 180) (fields_autoplaced)
    (effects (font (size 1.27 1.27)) (justify right))
    (property "Intersheetrefs" "${INTERSHEET_REFS}" (at -0.635 0.635 0)
      (effects (font (size 1.27 1.27)) hide)
    )
  )
  (global_label "GPIO25" (shape input) (at 200.66 163.83 0) (fields_autoplaced)
    (effects (font (size 1.27 1.27)) (justify left))
    (property "Intersheetrefs" "${INTERSHEET_REFS}" (at -8.255 3.175 0)
      (effects (font (size 1.27 1.27)) hide)
    )
  )
  (global_label "HDMI0_SCL" (shape input) (at 167.64 123.19 180) (fields_autoplaced)
    (effects (font (size 1.27 1.27)) (justify right))
    (property "Intersheetrefs" "${INTERSHEET_REFS}" (at 0.635 3.175 0)
      (effects (font (size 1.27 1.27)) hide)
    )
  )
  (global_label "HDMI0_CEC" (shape input) (at 167.64 128.27 180) (fields_autoplaced)
    (effects (font (size 1.27 1.27)) (justify right))
    (property "Intersheetrefs" "${INTERSHEET_REFS}" (at 0.635 3.175 0)
      (effects (font (size 1.27 1.27)) hide)
    )
  )
  (global_label "VCC5V0" (shape input) (at 167.64 90.17 180) (fields_autoplaced)
    (effects (font (size 1.27 1.27)) (justify right))
    (property "Intersheetrefs" "${INTERSHEET_REFS}" (at 6.985 3.175 0)
      (effects (font (size 1.27 1.27)) hide)
    )
  )
  (global_label "HDMI0_D1_N" (shape input) (at 167.64 146.05 180) (fields_autoplaced)
    (effects (font (size 1.27 1.27)) (justify right))
    (property "Intersheetrefs" "${INTERSHEET_REFS}" (at 0.635 3.175 0)
      (effects (font (size 1.27 1.27)) hide)
    )
  )
  (global_label "Adapter_TXD" (shape output) (at 200.66 125.73 0) (fields_autoplaced)
    (effects (font (size 1.27 1.27)) (justify left))
    (property "Intersheetrefs" "${INTERSHEET_REFS}" (at -8.255 3.175 0)
      (effects (font (size 1.27 1.27)) hide)
    )
  )
  (global_label "HDMI0_D0_P" (shape input) (at 167.64 151.13 180) (fields_autoplaced)
    (effects (font (size 1.27 1.27)) (justify right))
    (property "Intersheetrefs" "${INTERSHEET_REFS}" (at 0.635 3.175 0)
      (effects (font (size 1.27 1.27)) hide)
    )
  )
  (global_label "HDMI0_D0_N" (shape input) (at 167.64 153.67 180) (fields_autoplaced)
    (effects (font (size 1.27 1.27)) (justify right))
    (property "Intersheetrefs" "${INTERSHEET_REFS}" (at 0.635 3.175 0)
      (effects (font (size 1.27 1.27)) hide)
    )
  )
  (global_label "HDMI0_D1_P" (shape input) (at 167.64 143.51 180) (fields_autoplaced)
    (effects (font (size 1.27 1.27)) (justify right))
    (property "Intersheetrefs" "${INTERSHEET_REFS}" (at 0.635 3.175 0)
      (effects (font (size 1.27 1.27)) hide)
    )
  )
  (global_label "Adapter_USB_P" (shape bidirectional) (at 200.66 133.35 0) (fields_autoplaced)
    (effects (font (size 1.27 1.27)) (justify left))
    (property "Intersheetrefs" "${INTERSHEET_REFS}" (at -8.255 3.175 0)
      (effects (font (size 1.27 1.27)) hide)
    )
  )
  (global_label "SDA0" (shape input) (at 200.66 140.97 0) (fields_autoplaced)
    (effects (font (size 1.27 1.27)) (justify left))
    (property "Intersheetrefs" "${INTERSHEET_REFS}" (at -8.255 3.175 0)
      (effects (font (size 1.27 1.27)) hide)
    )
  )
  (global_label "HDMI0_HOTPLUG" (shape input) (at 167.64 130.81 180) (fields_autoplaced)
    (effects (font (size 1.27 1.27)) (justify right))
    (property "Intersheetrefs" "${INTERSHEET_REFS}" (at 0.635 3.175 0)
      (effects (font (size 1.27 1.27)) hide)
    )
  )
  (global_label "3V3_OUT" (shape input) (at 200.66 90.17 0) (fields_autoplaced)
    (effects (font (size 1.27 1.27)) (justify left))
    (property "Intersheetrefs" "${INTERSHEET_REFS}" (at -8.255 3.175 0)
      (effects (font (size 1.27 1.27)) hide)
    )
  )
  (global_label "3V3_SSD" (shape input) (at 274.32 99.06 0) (fields_autoplaced)
    (effects (font (size 1.27 1.27)) (justify left))
    (property "Intersheetrefs" "${INTERSHEET_REFS}" (at -0.635 0.635 0)
      (effects (font (size 1.27 1.27)) hide)
    )
  )
  (global_label "GPIO8" (shape input) (at 200.66 156.21 0) (fields_autoplaced)
    (effects (font (size 1.27 1.27)) (justify left))
    (property "Intersheetrefs" "${INTERSHEET_REFS}" (at -8.255 3.175 0)
      (effects (font (size 1.27 1.27)) hide)
    )
  )
  (global_label "GPIO24" (shape input) (at 200.66 161.29 0) (fields_autoplaced)
    (effects (font (size 1.27 1.27)) (justify left))
    (property "Intersheetrefs" "${INTERSHEET_REFS}" (at -8.255 3.175 0)
      (effects (font (size 1.27 1.27)) hide)
    )
  )
  (global_label "Adapter_USB_N" (shape bidirectional) (at 200.66 130.81 0) (fields_autoplaced)
    (effects (font (size 1.27 1.27)) (justify left))
    (property "Intersheetrefs" "${INTERSHEET_REFS}" (at -8.255 3.175 0)
      (effects (font (size 1.27 1.27)) hide)
    )
  )

  (symbol (lib_id "scalenode-cm4-baseboard:MP_Pad4.5mm_Drill2.2mm") (at 135.255 196.215 0) (unit 1)
    (in_bom no) (on_board yes) (dnp no) (fields_autoplaced)
    (property "Reference" "MP1" (at 144.78 194.945 0)
      (effects (font (size 1.27 1.27) (thickness 0.15)) (justify left))
    )
    (property "Value" "MP_Pad4.5mm_Drill2.2mm" (at 144.78 197.485 0)
      (effects (font (size 1.27 1.27) (thickness 0.15)) (justify left))
    )
    (property "Footprint" "scalenode-cm4-baseboard-footprints:MP_Pad4.5mm_Drill2.2mm" (at 153.035 203.835 0)
      (effects (font (size 1.27 1.27) (thickness 0.15)) (justify left bottom) hide)
    )
    (property "Datasheet" "" (at 152.095 211.785 0)
      (effects (font (size 1.27 1.27) (thickness 0.15)) (justify left bottom) hide)
    )
    (property "Manufacturer" "" (at 153.035 206.375 0)
      (effects (font (size 1.27 1.27) (thickness 0.15)) (justify left bottom) hide)
    )
    (property "Author" "Antmicro" (at 153.035 208.915 0)
      (effects (font (size 1.27 1.27) (thickness 0.15)) (justify left bottom) hide)
    )
    (property "License" "Apache-2.0" (at 153.035 211.455 0)
      (effects (font (size 1.27 1.27) (thickness 0.15)) (justify left bottom) hide)
    )
    (property "MPN" "" (at 135.255 196.215 0)
      (effects (font (size 1.27 1.27)) hide)
    )
    (pin "1")
    (instances
      (project "scalenode-cm4-baseboard"
        (path ""
          (reference "MP1") (unit 1)
        )
      )
    )
  )

  (symbol (lib_id "scalenode-cm4-baseboard:MP_Pad6.2mm_Drill2.75mm") (at 175.26 196.85 0) (unit 1)
    (in_bom no) (on_board yes) (dnp no) (fields_autoplaced)
    (property "Reference" "MP2" (at 184.15 195.58 0)
      (effects (font (size 1.27 1.27) (thickness 0.15)) (justify left))
    )
    (property "Value" "MP_Pad6.2mm_Drill2.75mm" (at 184.15 198.12 0)
      (effects (font (size 1.27 1.27) (thickness 0.15)) (justify left))
    )
    (property "Footprint" "scalenode-cm4-baseboard-footprints:MP_Pad6.2mm_Drill2.75mm" (at 190.5 207.01 0)
      (effects (font (size 1.27 1.27) (thickness 0.15)) (justify left bottom) hide)
    )
    (property "Datasheet" "" (at 192.1 212.42 0)
      (effects (font (size 1.27 1.27) (thickness 0.15)) (justify left bottom) hide)
    )
    (property "Manufacturer" "" (at 193.04 209.55 0)
      (effects (font (size 1.27 1.27) (thickness 0.15)) (justify left bottom) hide)
    )
    (property "Author" "Antmicro" (at 190.5 209.55 0)
      (effects (font (size 1.27 1.27) (thickness 0.15)) (justify left bottom) hide)
    )
    (property "License" "Apache-2.0" (at 190.5 212.09 0)
      (effects (font (size 1.27 1.27) (thickness 0.15)) (justify left bottom) hide)
    )
    (property "MPN" "" (at 175.26 196.85 0)
      (effects (font (size 1.27 1.27)) hide)
    )
    (pin "1")
    (instances
      (project "scalenode-cm4-baseboard"
        (path ""
          (reference "MP2") (unit 1)
        )
      )
    )
  )

  (symbol (lib_id "scalenode-cm4-baseboard:MP_Pad6.2mm_Drill2.75mm") (at 213.36 196.85 0) (unit 1)
    (in_bom no) (on_board yes) (dnp no) (fields_autoplaced)
    (property "Reference" "MP3" (at 222.25 195.58 0)
      (effects (font (size 1.27 1.27) (thickness 0.15)) (justify left))
    )
    (property "Value" "MP_Pad6.2mm_Drill2.75mm" (at 222.25 198.12 0)
      (effects (font (size 1.27 1.27) (thickness 0.15)) (justify left))
    )
    (property "Footprint" "scalenode-cm4-baseboard-footprints:MP_Pad6.2mm_Drill2.75mm" (at 228.6 207.01 0)
      (effects (font (size 1.27 1.27) (thickness 0.15)) (justify left bottom) hide)
    )
    (property "Datasheet" "" (at 230.2 212.42 0)
      (effects (font (size 1.27 1.27) (thickness 0.15)) (justify left bottom) hide)
    )
    (property "Manufacturer" "" (at 231.14 209.55 0)
      (effects (font (size 1.27 1.27) (thickness 0.15)) (justify left bottom) hide)
    )
    (property "Author" "Antmicro" (at 228.6 209.55 0)
      (effects (font (size 1.27 1.27) (thickness 0.15)) (justify left bottom) hide)
    )
    (property "License" "Apache-2.0" (at 228.6 212.09 0)
      (effects (font (size 1.27 1.27) (thickness 0.15)) (justify left bottom) hide)
    )
    (property "MPN" "" (at 213.36 196.85 0)
      (effects (font (size 1.27 1.27)) hide)
    )
    (pin "1")
    (instances
      (project "scalenode-cm4-baseboard"
        (path ""
          (reference "MP3") (unit 1)
        )
      )
    )
  )

  (symbol (lib_id "scalenode-cm4-baseboard:Hermaphroditic_Samtec_LSHM_2x30_LSHM-130-01-L-RH-A-S-K-TR") (at 172.72 90.17 0) (unit 1)
    (in_bom yes) (on_board yes) (dnp no) (fields_autoplaced)
    (property "Reference" "J10" (at 166.2648 82.55 0)
      (effects (font (size 1.27 1.27) (thickness 0.15)) (justify left bottom))
    )
    (property "Value" "Hermaphroditic_Samtec_LSHM_2x30_LSHM-130-01-L-RH-A-S-K-TR" (at 166.2648 85.09 0)
      (effects (font (size 1.27 1.27) (thickness 0.15)) (justify left bottom))
    )
    (property "Footprint" "scalenode-cm4-baseboard-footprints:Conn_Hermaphroditic_Samtec_LSHM_2x30_LSHM-130-01-XXX-RH-A-S-K-XX" (at 208.28 97.79 0)
      (effects (font (size 1.27 1.27) (thickness 0.15)) (justify left bottom) hide)
    )
    (property "Datasheet" "https://suddendocs.samtec.com/catalog_english/lshm_dh.pdf" (at 208.28 100.33 0)
      (effects (font (size 1.27 1.27) (thickness 0.15)) (justify left bottom) hide)
    )
    (property "MPN" "LSHM-130-01-L-RH-A-S-K-TR" (at 208.28 105.41 0)
      (effects (font (size 1.27 1.27) (thickness 0.15)) (justify left bottom) hide)
    )
    (property "Manufacturer" "Samtec" (at 208.28 102.87 0)
      (effects (font (size 1.27 1.27) (thickness 0.15)) (justify left bottom) hide)
    )
    (property "Author" "Antmicro" (at 208.28 107.95 0)
      (effects (font (size 1.27 1.27) (thickness 0.15)) (justify left bottom) hide)
    )
    (property "License" "Apache-2.0" (at 208.28 110.49 0)
      (effects (font (size 1.27 1.27) (thickness 0.15)) (justify left bottom) hide)
    )
    (pin "01")
    (pin "02")
    (pin "03")
    (pin "04")
    (pin "05")
    (pin "06")
    (pin "07")
    (pin "08")
    (pin "09")
    (pin "10")
    (pin "11")
    (pin "12")
    (pin "13")
    (pin "14")
    (pin "15")
    (pin "16")
    (pin "17")
    (pin "18")
    (pin "19")
    (pin "20")
    (pin "21")
    (pin "22")
    (pin "23")
    (pin "24")
    (pin "25")
    (pin "26")
    (pin "27")
    (pin "28")
    (pin "29")
    (pin "30")
    (pin "31")
    (pin "32")
    (pin "33")
    (pin "34")
    (pin "35")
    (pin "36")
    (pin "37")
    (pin "38")
    (pin "39")
    (pin "40")
    (pin "41")
    (pin "42")
    (pin "43")
    (pin "44")
    (pin "45")
    (pin "46")
    (pin "47")
    (pin "48")
    (pin "49")
    (pin "50")
    (pin "51")
    (pin "52")
    (pin "53")
    (pin "54")
    (pin "55")
    (pin "56")
    (pin "57")
    (pin "58")
    (pin "59")
    (pin "60")
    (pin "S1")
    (pin "S2")
    (instances
      (project "scalenode-cm4-baseboard"
        (path ""
          (reference "J10") (unit 1)
        )
      )
    )
  )

  (symbol (lib_id "scalenode-cm4-baseboard:R_0R_1206") (at 264.16 99.06 0) (unit 1)
    (in_bom yes) (on_board yes) (dnp no)
    (property "Reference" "R62" (at 262.89 97.79 0)
      (effects (font (size 1.27 1.27) (thickness 0.15)) (justify left bottom))
    )
    (property "Value" "R_0R_1206" (at 284.48 111.76 0)
      (effects (font (size 1.27 1.27) (thickness 0.15)) (justify left bottom) hide)
    )
    (property "Footprint" "scalenode-cm4-baseboard-footprints:R_1206_3216Metric" (at 284.48 114.3 0)
      (effects (font (size 1.27 1.27) (thickness 0.15)) (justify left bottom) hide)
    )
    (property "Datasheet" "https://www.farnell.com/datasheets/2860635.pdf" (at 284.48 116.84 0)
      (effects (font (size 1.27 1.27) (thickness 0.15)) (justify left bottom) hide)
    )
    (property "Manufacturer" "Multicomp Pro" (at 284.48 121.92 0)
      (effects (font (size 1.27 1.27) (thickness 0.15)) (justify left bottom) hide)
    )
    (property "MPN" "MCMR12X000_PTL" (at 284.48 119.38 0)
      (effects (font (size 1.27 1.27) (thickness 0.15)) (justify left bottom) hide)
    )
    (property "Val" "0R" (at 267.97 97.79 0)
      (effects (font (size 1.27 1.27) (thickness 0.15)) (justify left bottom))
    )
    (property "License" "Apache-2.0" (at 284.48 124.46 0)
      (effects (font (size 1.27 1.27) (thickness 0.15)) (justify left bottom) hide)
    )
    (property "Author" "Antmicro" (at 284.48 127 0)
      (effects (font (size 1.27 1.27) (thickness 0.15)) (justify left bottom) hide)
    )
    (property "Tolerance" "~" (at 284.48 109.22 0)
      (effects (font (size 1.27 1.27)) (justify left bottom) hide)
    )
    (property "Current" "2A" (at 284.48 129.54 0)
      (effects (font (size 1.27 1.27) (thickness 0.15)) (justify left bottom) hide)
    )
    (pin "1")
    (pin "2")
    (instances
      (project "scalenode-cm4-baseboard"
        (path ""
          (reference "R62") (unit 1)
        )
      )
    )
  )

  (symbol (lib_id "scalenode-cm4-baseboard:GND") (at 198.12 173.99 0) (unit 1)
    (in_bom yes) (on_board yes) (dnp no) (fields_autoplaced)
    (property "Reference" "#PWR0110" (at 207.01 176.53 0)
      (effects (font (size 1.27 1.27) (thickness 0.15)) (justify left bottom) hide)
    )
    (property "Value" "GND" (at 196.1098 179.07 0)
      (effects (font (size 1.27 1.27) (thickness 0.15)) (justify left bottom))
    )
    (property "Footprint" "" (at 207.01 181.61 0)
      (effects (font (size 1.27 1.27) (thickness 0.15)) (justify left bottom) hide)
    )
    (property "Datasheet" "" (at 207.01 186.69 0)
      (effects (font (size 1.27 1.27) (thickness 0.15)) (justify left bottom) hide)
    )
    (property "Author" "Antmicro" (at 207.01 181.61 0)
      (effects (font (size 1.27 1.27) (thickness 0.15)) (justify left bottom) hide)
    )
    (property "License" "Apache-2.0" (at 207.01 184.15 0)
      (effects (font (size 1.27 1.27) (thickness 0.15)) (justify left bottom) hide)
    )
    (pin "1")
    (instances
      (project "scalenode-cm4-baseboard"
        (path ""
          (reference "#PWR0110") (unit 1)
        )
      )
    )
  )

  (symbol (lib_id "scalenode-cm4-baseboard:R_0R_1206") (at 264.16 104.14 0) (unit 1)
    (in_bom no) (on_board yes) (dnp yes)
    (property "Reference" "R63" (at 262.89 107.95 0)
      (effects (font (size 1.27 1.27) (thickness 0.15)) (justify left bottom))
    )
    (property "Value" "R_0R_1206" (at 284.48 116.84 0)
      (effects (font (size 1.27 1.27) (thickness 0.15)) (justify left bottom) hide)
    )
    (property "Footprint" "scalenode-cm4-baseboard-footprints:R_1206_3216Metric" (at 284.48 119.38 0)
      (effects (font (size 1.27 1.27) (thickness 0.15)) (justify left bottom) hide)
    )
    (property "Datasheet" "https://www.farnell.com/datasheets/2860635.pdf" (at 284.48 121.92 0)
      (effects (font (size 1.27 1.27) (thickness 0.15)) (justify left bottom) hide)
    )
    (property "Manufacturer" "Multicomp Pro" (at 284.48 127 0)
      (effects (font (size 1.27 1.27) (thickness 0.15)) (justify left bottom) hide)
    )
    (property "MPN" "MCMR12X000_PTL" (at 284.48 124.46 0)
      (effects (font (size 1.27 1.27) (thickness 0.15)) (justify left bottom) hide)
    )
    (property "Val" "0R" (at 267.97 107.95 0)
      (effects (font (size 1.27 1.27) (thickness 0.15)) (justify left bottom))
    )
    (property "DNP" "DNP" (at 266.7 104.14 0)
      (effects (font (size 1 1)))
    )
    (property "License" "Apache-2.0" (at 284.48 129.54 0)
      (effects (font (size 1.27 1.27) (thickness 0.15)) (justify left bottom) hide)
    )
    (property "Author" "Antmicro" (at 284.48 132.08 0)
      (effects (font (size 1.27 1.27) (thickness 0.15)) (justify left bottom) hide)
    )
    (property "Tolerance" "~" (at 284.48 114.3 0)
      (effects (font (size 1.27 1.27)) (justify left bottom) hide)
    )
    (property "Current" "2A" (at 284.48 134.62 0)
      (effects (font (size 1.27 1.27) (thickness 0.15)) (justify left bottom) hide)
    )
    (pin "1")
    (pin "2")
    (instances
      (project "scalenode-cm4-baseboard"
        (path ""
          (reference "R63") (unit 1)
        )
      )
    )
  )

  (symbol (lib_id "scalenode-cm4-baseboard:GND") (at 170.18 173.99 0) (unit 1)
    (in_bom yes) (on_board yes) (dnp no) (fields_autoplaced)
    (property "Reference" "#PWR0111" (at 179.07 176.53 0)
      (effects (font (size 1.27 1.27) (thickness 0.15)) (justify left bottom) hide)
    )
    (property "Value" "GND" (at 168.1698 179.07 0)
      (effects (font (size 1.27 1.27) (thickness 0.15)) (justify left bottom))
    )
    (property "Footprint" "" (at 179.07 181.61 0)
      (effects (font (size 1.27 1.27) (thickness 0.15)) (justify left bottom) hide)
    )
    (property "Datasheet" "" (at 179.07 186.69 0)
      (effects (font (size 1.27 1.27) (thickness 0.15)) (justify left bottom) hide)
    )
    (property "Author" "Antmicro" (at 179.07 181.61 0)
      (effects (font (size 1.27 1.27) (thickness 0.15)) (justify left bottom) hide)
    )
    (property "License" "Apache-2.0" (at 179.07 184.15 0)
      (effects (font (size 1.27 1.27) (thickness 0.15)) (justify left bottom) hide)
    )
    (pin "1")
    (instances
      (project "scalenode-cm4-baseboard"
        (path ""
          (reference "#PWR0111") (unit 1)
        )
      )
    )
  )
)
